(kicad_pcb
	(version 20260206)
	(generator "pcbnew")
	(generator_version "10.0")
	(general
		(thickness 1.6)
		(legacy_teardrops no)
	)
	(paper "A4")
	(title_block
		(title "04192023_DAF0TMB3IC0_F0TG_MB_C_brd_V02_OCP.brd")
		(comment 1 "Grand Teton / footprints 7540-7546 of 8354")
	)
	(layers
		(0 "F.Cu" signal "TOP")
		(4 "In1.Cu" signal "GND")
		(6 "In2.Cu" signal "IN1")
		(8 "In3.Cu" signal "GND1")
		(10 "In4.Cu" signal "IN2")
		(12 "In5.Cu" signal "GND2")
		(14 "In6.Cu" signal "IN3")
		(16 "In7.Cu" signal "GND3")
		(18 "In8.Cu" signal "VCC")
		(20 "In9.Cu" signal "VCC1")
		(22 "In10.Cu" signal "GND4")
		(24 "In11.Cu" signal "IN4")
		(26 "In12.Cu" signal "GND5")
		(28 "In13.Cu" signal "IN5")
		(30 "In14.Cu" signal "GND6")
		(32 "In15.Cu" signal "IN6")
		(34 "In16.Cu" signal "GND7")
		(2 "B.Cu" signal "BOTTOM")
		(9 "F.Adhes" user "F.Adhesive")
		(11 "B.Adhes" user "B.Adhesive")
		(13 "F.Paste" user "Package Geometry/Pastemask Top")
		(15 "B.Paste" user "Package Geometry/Pastemask Bottom")
		(5 "F.SilkS" user "Ref Des/Silkscreen Top")
		(7 "B.SilkS" user "Ref Des/Silkscreen Bottom")
		(1 "F.Mask" user "Board Geometry/Soldermask Top")
		(3 "B.Mask" user "Board Geometry/Soldermask Bottom")
		(17 "Dwgs.User" user "User.Drawings")
		(19 "Cmts.User" user "User.Comments")
		(21 "Eco1.User" user "User.Eco1")
		(23 "Eco2.User" user "User.Eco2")
		(25 "Edge.Cuts" user "Board Geometry/Outline")
		(27 "Margin" user)
		(31 "F.CrtYd" user "Package Geometry/Place Bound Top")
		(29 "B.CrtYd" user "Package Geometry/Place Bound Bottom")
		(35 "F.Fab" user "Ref Des/Assembly Top")
		(33 "B.Fab" user "Ref Des/Assembly Bottom")
	)
	(footprint ""
		(layer "B.Cu")
		(at 182.8673 -13.60043 -90)
		(property "Reference" "R6007"
			(at 0 0 90)
			(layer "B.SilkS")
			(hide yes)
			(effects
				(font
					(size 1.27 1.27)
				)
				(justify mirror)
			)
		)
		(property "Value" ""
			(at 0 0 90)
			(layer "B.Fab")
			(effects
				(font
					(size 1.27 1.27)
				)
				(justify mirror)
			)
		)
		(duplicate_pad_numbers_are_jumpers no)
		(fp_line
			(start -0.7874 0.4064)
			(end 0.7874 0.4064)
			(stroke
				(width 0.1524)
				(type default)
			)
			(layer "B.SilkS")
		)
		(fp_line
			(start 0.7874 0.4064)
			(end 0.7874 -0.4064)
			(stroke
				(width 0.1524)
				(type default)
			)
			(layer "B.SilkS")
		)
		(fp_line
			(start -0.7874 -0.4064)
			(end -0.7874 0.4064)
			(stroke
				(width 0.1524)
				(type default)
			)
			(layer "B.SilkS")
		)
		(fp_line
			(start 0.7874 -0.4064)
			(end -0.7874 -0.4064)
			(stroke
				(width 0.1524)
				(type default)
			)
			(layer "B.SilkS")
		)
		(fp_line
			(start -0.67945 0.3048)
			(end -0.120396 0.3048)
			(stroke
				(width 0.1)
				(type default)
			)
			(layer "B.Fab")
		)
		(fp_line
			(start -0.120396 0.3048)
			(end -0.120396 0.2794)
			(stroke
				(width 0.1)
				(type default)
			)
			(layer "B.Fab")
		)
		(fp_line
			(start 0.12065 0.3048)
			(end 0.67945 0.3048)
			(stroke
				(width 0.1)
				(type default)
			)
			(layer "B.Fab")
		)
		(fp_line
			(start 0.67945 0.3048)
			(end 0.67945 -0.305054)
			(stroke
				(width 0.1)
				(type default)
			)
			(layer "B.Fab")
		)
		(fp_line
			(start -0.120396 0.2794)
			(end 0.12065 0.2794)
			(stroke
				(width 0.1)
				(type default)
			)
			(layer "B.Fab")
		)
		(fp_line
			(start 0.12065 0.2794)
			(end 0.12065 0.3048)
			(stroke
				(width 0.1)
				(type default)
			)
			(layer "B.Fab")
		)
		(fp_line
			(start -0.12065 -0.2794)
			(end -0.12065 -0.3048)
			(stroke
				(width 0.1)
				(type default)
			)
			(layer "B.Fab")
		)
		(fp_line
			(start 0.12065 -0.2794)
			(end -0.12065 -0.2794)
			(stroke
				(width 0.1)
				(type default)
			)
			(layer "B.Fab")
		)
		(fp_line
			(start -0.67945 -0.3048)
			(end -0.67945 0.3048)
			(stroke
				(width 0.1)
				(type default)
			)
			(layer "B.Fab")
		)
		(fp_line
			(start -0.12065 -0.3048)
			(end -0.67945 -0.3048)
			(stroke
				(width 0.1)
				(type default)
			)
			(layer "B.Fab")
		)
		(fp_line
			(start 0.12065 -0.305054)
			(end 0.12065 -0.2794)
			(stroke
				(width 0.1)
				(type default)
			)
			(layer "B.Fab")
		)
		(fp_line
			(start 0.67945 -0.305054)
			(end 0.12065 -0.305054)
			(stroke
				(width 0.1)
				(type default)
			)
			(layer "B.Fab")
		)
		(pad "1" smd circle
			(at 0.40005 0 90)
			(size 0 0)
			(layers "B.Cu" "B.Mask" "B.Paste")
			(net "I3C_SCM_3_SDA")
		)
		(pad "2" smd circle
			(at -0.40005 0 90)
			(size 0 0)
			(layers "B.Cu" "B.Mask" "B.Paste")
			(net "I3C_SCM_3_R_SDA")
		)
	)
	(footprint ""
		(layer "B.Cu")
		(at 276.54377 -346.784168 90)
		(property "Reference" "PC182_4"
			(at 0 0 90)
			(layer "B.SilkS")
			(hide yes)
			(effects
				(font
					(size 1.27 1.27)
				)
				(justify mirror)
			)
		)
		(property "Value" ""
			(at 0 0 90)
			(layer "B.Fab")
			(effects
				(font
					(size 1.27 1.27)
				)
				(justify mirror)
			)
		)
		(duplicate_pad_numbers_are_jumpers no)
		(fp_line
			(start 1.524 -0.762)
			(end -1.524 -0.762)
			(stroke
				(width 0.1524)
				(type default)
			)
			(layer "B.SilkS")
		)
		(fp_line
			(start -1.524 -0.762)
			(end -1.524 0.762)
			(stroke
				(width 0.1524)
				(type default)
			)
			(layer "B.SilkS")
		)
		(fp_line
			(start 1.524 0.762)
			(end 1.524 -0.762)
			(stroke
				(width 0.1524)
				(type default)
			)
			(layer "B.SilkS")
		)
		(fp_line
			(start -1.524 0.762)
			(end 1.524 0.762)
			(stroke
				(width 0.1524)
				(type default)
			)
			(layer "B.SilkS")
		)
		(fp_line
			(start 1.1049 -0.724916)
			(end 1.1049 0.724916)
			(stroke
				(width 0.1)
				(type default)
			)
			(layer "B.Fab")
		)
		(fp_line
			(start -1.1049 -0.724916)
			(end 1.1049 -0.724916)
			(stroke
				(width 0.1)
				(type default)
			)
			(layer "B.Fab")
		)
		(fp_line
			(start 1.1049 0.724916)
			(end -1.1049 0.724916)
			(stroke
				(width 0.1)
				(type default)
			)
			(layer "B.Fab")
		)
		(fp_line
			(start -1.1049 0.724916)
			(end -1.1049 -0.724916)
			(stroke
				(width 0.1)
				(type default)
			)
			(layer "B.Fab")
		)
		(pad "1" smd rect
			(at 0.889 0 90)
			(size 1.016 1.27)
			(layers "B.Cu" "B.Mask" "B.Paste")
			(net "SW_P12V_AUX_PVDDIO_P0_FLT")
		)
		(pad "2" smd rect
			(at -0.889 0 90)
			(size 1.016 1.27)
			(layers "B.Cu" "B.Mask" "B.Paste")
			(net "GND")
		)
	)
	(footprint ""
		(layer "B.Cu")
		(at 336.279744 -156.059886 180)
		(property "Reference" "PC114"
			(at 0 0 0)
			(layer "B.SilkS")
			(hide yes)
			(effects
				(font
					(size 1.27 1.27)
				)
				(justify mirror)
			)
		)
		(property "Value" ""
			(at 0 0 0)
			(layer "B.Fab")
			(effects
				(font
					(size 1.27 1.27)
				)
				(justify mirror)
			)
		)
		(duplicate_pad_numbers_are_jumpers no)
		(fp_line
			(start 1.524 0.762)
			(end 1.524 -0.762)
			(stroke
				(width 0.1524)
				(type default)
			)
			(layer "B.SilkS")
		)
		(fp_line
			(start 1.524 -0.762)
			(end -1.524 -0.762)
			(stroke
				(width 0.1524)
				(type default)
			)
			(layer "B.SilkS")
		)
		(fp_line
			(start -1.524 0.762)
			(end 1.524 0.762)
			(stroke
				(width 0.1524)
				(type default)
			)
			(layer "B.SilkS")
		)
		(fp_line
			(start -1.524 -0.762)
			(end -1.524 0.762)
			(stroke
				(width 0.1524)
				(type default)
			)
			(layer "B.SilkS")
		)
		(fp_line
			(start 1.1049 0.724916)
			(end -1.1049 0.724916)
			(stroke
				(width 0.1)
				(type default)
			)
			(layer "B.Fab")
		)
		(fp_line
			(start 1.1049 -0.724916)
			(end 1.1049 0.724916)
			(stroke
				(width 0.1)
				(type default)
			)
			(layer "B.Fab")
		)
		(fp_line
			(start -1.1049 0.724916)
			(end -1.1049 -0.724916)
			(stroke
				(width 0.1)
				(type default)
			)
			(layer "B.Fab")
		)
		(fp_line
			(start -1.1049 -0.724916)
			(end 1.1049 -0.724916)
			(stroke
				(width 0.1)
				(type default)
			)
			(layer "B.Fab")
		)
		(pad "1" smd rect
			(at 0.889 0 180)
			(size 1.016 1.27)
			(layers "B.Cu" "B.Mask" "B.Paste")
			(net "PVDD18_S5_P0")
		)
		(pad "2" smd rect
			(at -0.889 0 180)
			(size 1.016 1.27)
			(layers "B.Cu" "B.Mask" "B.Paste")
			(net "GND")
		)
	)
	(footprint ""
		(layer "B.Cu")
		(at 75.473814 -9.50468 180)
		(property "Reference" "R3174"
			(at 0 0 0)
			(layer "B.SilkS")
			(hide yes)
			(effects
				(font
					(size 1.27 1.27)
				)
				(justify mirror)
			)
		)
		(property "Value" ""
			(at 0 0 0)
			(layer "B.Fab")
			(effects
				(font
					(size 1.27 1.27)
				)
				(justify mirror)
			)
		)
		(duplicate_pad_numbers_are_jumpers no)
		(fp_line
			(start 0.7874 0.4064)
			(end 0.7874 -0.4064)
			(stroke
				(width 0.1524)
				(type default)
			)
			(layer "B.SilkS")
		)
		(fp_line
			(start 0.7874 -0.4064)
			(end -0.7874 -0.4064)
			(stroke
				(width 0.1524)
				(type default)
			)
			(layer "B.SilkS")
		)
		(fp_line
			(start -0.7874 0.4064)
			(end 0.7874 0.4064)
			(stroke
				(width 0.1524)
				(type default)
			)
			(layer "B.SilkS")
		)
		(fp_line
			(start -0.7874 -0.4064)
			(end -0.7874 0.4064)
			(stroke
				(width 0.1524)
				(type default)
			)
			(layer "B.SilkS")
		)
		(fp_line
			(start 0.67945 0.3048)
			(end 0.67945 -0.305054)
			(stroke
				(width 0.1)
				(type default)
			)
			(layer "B.Fab")
		)
		(fp_line
			(start 0.67945 -0.305054)
			(end 0.12065 -0.305054)
			(stroke
				(width 0.1)
				(type default)
			)
			(layer "B.Fab")
		)
		(fp_line
			(start 0.12065 0.3048)
			(end 0.67945 0.3048)
			(stroke
				(width 0.1)
				(type default)
			)
			(layer "B.Fab")
		)
		(fp_line
			(start 0.12065 0.2794)
			(end 0.12065 0.3048)
			(stroke
				(width 0.1)
				(type default)
			)
			(layer "B.Fab")
		)
		(fp_line
			(start 0.12065 -0.2794)
			(end -0.12065 -0.2794)
			(stroke
				(width 0.1)
				(type default)
			)
			(layer "B.Fab")
		)
		(fp_line
			(start 0.12065 -0.305054)
			(end 0.12065 -0.2794)
			(stroke
				(width 0.1)
				(type default)
			)
			(layer "B.Fab")
		)
		(fp_line
			(start -0.120396 0.3048)
			(end -0.120396 0.2794)
			(stroke
				(width 0.1)
				(type default)
			)
			(layer "B.Fab")
		)
		(fp_line
			(start -0.120396 0.2794)
			(end 0.12065 0.2794)
			(stroke
				(width 0.1)
				(type default)
			)
			(layer "B.Fab")
		)
		(fp_line
			(start -0.12065 -0.2794)
			(end -0.12065 -0.3048)
			(stroke
				(width 0.1)
				(type default)
			)
			(layer "B.Fab")
		)
		(fp_line
			(start -0.12065 -0.3048)
			(end -0.67945 -0.3048)
			(stroke
				(width 0.1)
				(type default)
			)
			(layer "B.Fab")
		)
		(fp_line
			(start -0.67945 0.3048)
			(end -0.120396 0.3048)
			(stroke
				(width 0.1)
				(type default)
			)
			(layer "B.Fab")
		)
		(fp_line
			(start -0.67945 -0.3048)
			(end -0.67945 0.3048)
			(stroke
				(width 0.1)
				(type default)
			)
			(layer "B.Fab")
		)
		(pad "1" smd circle
			(at 0.40005 0)
			(size 0 0)
			(layers "B.Cu" "B.Mask" "B.Paste")
			(net "SGPIO_OCP_V3_2_DATAIN")
		)
		(pad "2" smd circle
			(at -0.40005 0)
			(size 0 0)
			(layers "B.Cu" "B.Mask" "B.Paste")
			(net "P3V3_OCP_V3_2")
		)
	)
	(footprint ""
		(layer "B.Cu")
		(at 286.893 -425.958 -90)
		(property "Reference" "R2725"
			(at 0 0 90)
			(layer "B.SilkS")
			(hide yes)
			(effects
				(font
					(size 1.27 1.27)
				)
				(justify mirror)
			)
		)
		(property "Value" ""
			(at 0 0 90)
			(layer "B.Fab")
			(effects
				(font
					(size 1.27 1.27)
				)
				(justify mirror)
			)
		)
		(duplicate_pad_numbers_are_jumpers no)
		(fp_line
			(start -0.7874 0.4064)
			(end 0.7874 0.4064)
			(stroke
				(width 0.1524)
				(type default)
			)
			(layer "B.SilkS")
		)
		(fp_line
			(start 0.7874 0.4064)
			(end 0.7874 -0.4064)
			(stroke
				(width 0.1524)
				(type default)
			)
			(layer "B.SilkS")
		)
		(fp_line
			(start -0.7874 -0.4064)
			(end -0.7874 0.4064)
			(stroke
				(width 0.1524)
				(type default)
			)
			(layer "B.SilkS")
		)
		(fp_line
			(start 0.7874 -0.4064)
			(end -0.7874 -0.4064)
			(stroke
				(width 0.1524)
				(type default)
			)
			(layer "B.SilkS")
		)
		(fp_line
			(start -0.67945 0.3048)
			(end -0.120396 0.3048)
			(stroke
				(width 0.1)
				(type default)
			)
			(layer "B.Fab")
		)
		(fp_line
			(start -0.120396 0.3048)
			(end -0.120396 0.2794)
			(stroke
				(width 0.1)
				(type default)
			)
			(layer "B.Fab")
		)
		(fp_line
			(start 0.12065 0.3048)
			(end 0.67945 0.3048)
			(stroke
				(width 0.1)
				(type default)
			)
			(layer "B.Fab")
		)
		(fp_line
			(start 0.67945 0.3048)
			(end 0.67945 -0.305054)
			(stroke
				(width 0.1)
				(type default)
			)
			(layer "B.Fab")
		)
		(fp_line
			(start -0.120396 0.2794)
			(end 0.12065 0.2794)
			(stroke
				(width 0.1)
				(type default)
			)
			(layer "B.Fab")
		)
		(fp_line
			(start 0.12065 0.2794)
			(end 0.12065 0.3048)
			(stroke
				(width 0.1)
				(type default)
			)
			(layer "B.Fab")
		)
		(fp_line
			(start -0.12065 -0.2794)
			(end -0.12065 -0.3048)
			(stroke
				(width 0.1)
				(type default)
			)
			(layer "B.Fab")
		)
		(fp_line
			(start 0.12065 -0.2794)
			(end -0.12065 -0.2794)
			(stroke
				(width 0.1)
				(type default)
			)
			(layer "B.Fab")
		)
		(fp_line
			(start -0.67945 -0.3048)
			(end -0.67945 0.3048)
			(stroke
				(width 0.1)
				(type default)
			)
			(layer "B.Fab")
		)
		(fp_line
			(start -0.12065 -0.3048)
			(end -0.67945 -0.3048)
			(stroke
				(width 0.1)
				(type default)
			)
			(layer "B.Fab")
		)
		(fp_line
			(start 0.12065 -0.305054)
			(end 0.12065 -0.2794)
			(stroke
				(width 0.1)
				(type default)
			)
			(layer "B.Fab")
		)
		(fp_line
			(start 0.67945 -0.305054)
			(end 0.12065 -0.305054)
			(stroke
				(width 0.1)
				(type default)
			)
			(layer "B.Fab")
		)
		(pad "1" smd circle
			(at 0.40005 0 90)
			(size 0 0)
			(layers "B.Cu" "B.Mask" "B.Paste")
			(net "I3C_BMC_SWB_R_SCL")
		)
		(pad "2" smd circle
			(at -0.40005 0 90)
			(size 0 0)
			(layers "B.Cu" "B.Mask" "B.Paste")
			(net "I3C_BMC_SWB_BUF_R_SCL")
		)
	)
	(footprint ""
		(layer "B.Cu")
		(at 299.905928 -339.885528 -90)
		(property "Reference" "PC162"
			(at 9.619996 -0.997966 270)
			(unlocked yes)
			(layer "B.SilkS")
			(effects
				(font
					(size 0.7874 0.5842)
					(thickness 0.1524)
				)
				(justify left mirror)
			)
		)
		(property "Value" ""
			(at 0 0 90)
			(layer "B.Fab")
			(effects
				(font
					(size 1.27 1.27)
				)
				(justify mirror)
			)
		)
		(duplicate_pad_numbers_are_jumpers no)
		(fp_line
			(start -4.533392 2.249932)
			(end 4.533392 2.249932)
			(stroke
				(width 0.1524)
				(type default)
			)
			(layer "B.SilkS")
		)
		(fp_line
			(start 4.533392 2.249932)
			(end 4.533392 -2.249932)
			(stroke
				(width 0.1524)
				(type default)
			)
			(layer "B.SilkS")
		)
		(fp_line
			(start -4.533392 -2.249932)
			(end -4.533392 2.249932)
			(stroke
				(width 0.1524)
				(type default)
			)
			(layer "B.SilkS")
		)
		(fp_line
			(start 4.533392 -2.249932)
			(end -4.533392 -2.249932)
			(stroke
				(width 0.1524)
				(type default)
			)
			(layer "B.SilkS")
		)
		(fp_rect
			(start 5.39242 2.326132)
			(end 4.533392 -2.326132)
			(stroke
				(width 0)
				(type default)
			)
			(fill yes)
			(layer "B.SilkS")
		)
		(fp_line
			(start -3.750056 2.249932)
			(end 3.750056 2.249932)
			(stroke
				(width 0.1)
				(type default)
			)
			(layer "B.Fab")
		)
		(fp_line
			(start 3.750056 2.249932)
			(end 3.750056 -2.249932)
			(stroke
				(width 0.1)
				(type default)
			)
			(layer "B.Fab")
		)
		(fp_line
			(start -3.750056 -2.249932)
			(end -3.750056 2.249932)
			(stroke
				(width 0.1)
				(type default)
			)
			(layer "B.Fab")
		)
		(fp_line
			(start 3.750056 -2.249932)
			(end -3.750056 -2.249932)
			(stroke
				(width 0.1)
				(type default)
			)
			(layer "B.Fab")
		)
		(fp_text user "-"
			(at -4.607814 2.00787 270)
			(unlocked yes)
			(layer "B.SilkS")
			(effects
				(font
					(size 1.905 1.4224)
					(thickness 0.1524)
				)
				(justify left mirror)
			)
		)
		(fp_text user "+"
			(at 6.322314 0.786384 180)
			(unlocked yes)
			(layer "B.SilkS")
			(effects
				(font
					(size 1.905 1.4224)
					(thickness 0.1524)
				)
				(justify left mirror)
			)
		)
		(fp_text user "+"
			(at 6.322314 0.786384 180)
			(unlocked yes)
			(layer "B.Fab")
			(effects
				(font
					(size 1.905 1.4224)
					(thickness 0.1524)
				)
				(justify left mirror)
			)
		)
		(fp_text user "-"
			(at -4.8514 -0.14605 270)
			(unlocked yes)
			(layer "B.Fab")
			(effects
				(font
					(size 1.905 1.4224)
					(thickness 0.1524)
				)
				(justify left mirror)
			)
		)
		(pad "1" smd rect
			(at 3.199892 0 90)
			(size 2.413 2.8194)
			(layers "B.Cu" "B.Mask" "B.Paste")
			(net "PVDDIO_P0")
		)
		(pad "2" smd rect
			(at -3.199892 0 90)
			(size 2.413 2.8194)
			(layers "B.Cu" "B.Mask" "B.Paste")
			(net "GND")
		)
	)
	(footprint ""
		(layer "B.Cu")
		(at 308.379876 -66.708782 90)
		(property "Reference" "R6246"
			(at 0 0 90)
			(layer "B.SilkS")
			(hide yes)
			(effects
				(font
					(size 1.27 1.27)
				)
				(justify mirror)
			)
		)
		(property "Value" ""
			(at 0 0 90)
			(layer "B.Fab")
			(effects
				(font
					(size 1.27 1.27)
				)
				(justify mirror)
			)
		)
		(duplicate_pad_numbers_are_jumpers no)
		(fp_line
			(start 0.7874 -0.4064)
			(end -0.7874 -0.4064)
			(stroke
				(width 0.1524)
				(type default)
			)
			(layer "B.SilkS")
		)
		(fp_line
			(start -0.7874 -0.4064)
			(end -0.7874 0.4064)
			(stroke
				(width 0.1524)
				(type default)
			)
			(layer "B.SilkS")
		)
		(fp_line
			(start 0.7874 0.4064)
			(end 0.7874 -0.4064)
			(stroke
				(width 0.1524)
				(type default)
			)
			(layer "B.SilkS")
		)
		(fp_line
			(start -0.7874 0.4064)
			(end 0.7874 0.4064)
			(stroke
				(width 0.1524)
				(type default)
			)
			(layer "B.SilkS")
		)
		(fp_line
			(start 0.67945 -0.305054)
			(end 0.12065 -0.305054)
			(stroke
				(width 0.1)
				(type default)
			)
			(layer "B.Fab")
		)
		(fp_line
			(start 0.12065 -0.305054)
			(end 0.12065 -0.2794)
			(stroke
				(width 0.1)
				(type default)
			)
			(layer "B.Fab")
		)
		(fp_line
			(start -0.12065 -0.3048)
			(end -0.67945 -0.3048)
			(stroke
				(width 0.1)
				(type default)
			)
			(layer "B.Fab")
		)
		(fp_line
			(start -0.67945 -0.3048)
			(end -0.67945 0.3048)
			(stroke
				(width 0.1)
				(type default)
			)
			(layer "B.Fab")
		)
		(fp_line
			(start 0.12065 -0.2794)
			(end -0.12065 -0.2794)
			(stroke
				(width 0.1)
				(type default)
			)
			(layer "B.Fab")
		)
		(fp_line
			(start -0.12065 -0.2794)
			(end -0.12065 -0.3048)
			(stroke
				(width 0.1)
				(type default)
			)
			(layer "B.Fab")
		)
		(fp_line
			(start 0.12065 0.2794)
			(end 0.12065 0.3048)
			(stroke
				(width 0.1)
				(type default)
			)
			(layer "B.Fab")
		)
		(fp_line
			(start -0.120396 0.2794)
			(end 0.12065 0.2794)
			(stroke
				(width 0.1)
				(type default)
			)
			(layer "B.Fab")
		)
		(fp_line
			(start 0.67945 0.3048)
			(end 0.67945 -0.305054)
			(stroke
				(width 0.1)
				(type default)
			)
			(layer "B.Fab")
		)
		(fp_line
			(start 0.12065 0.3048)
			(end 0.67945 0.3048)
			(stroke
				(width 0.1)
				(type default)
			)
			(layer "B.Fab")
		)
		(fp_line
			(start -0.120396 0.3048)
			(end -0.120396 0.2794)
			(stroke
				(width 0.1)
				(type default)
			)
			(layer "B.Fab")
		)
		(fp_line
			(start -0.67945 0.3048)
			(end -0.120396 0.3048)
			(stroke
				(width 0.1)
				(type default)
			)
			(layer "B.Fab")
		)
		(pad "1" smd circle
			(at 0.40005 0 270)
			(size 0 0)
			(layers "B.Cu" "B.Mask" "B.Paste")
			(net "LED_PWRGD_P1V2_AUX")
		)
		(pad "2" smd circle
			(at -0.40005 0 270)
			(size 0 0)
			(layers "B.Cu" "B.Mask" "B.Paste")
			(net "P3V3_AUX")
		)
	)
)
